(kicad_pcb
	(version 20260206)
	(generator "pcbnew")
	(generator_version "10.0")
	(general
		(thickness 1.6)
		(legacy_teardrops no)
	)
	(paper "A4")
	(title_block
		(title "Wiwynn_Tioga_Pass_MB.brd")
		(comment 1 "Tioga Pass / footprints 4580-4586 of 4770")
	)
	(layers
		(0 "F.Cu" signal "TOP")
		(4 "In1.Cu" signal "L2GND")
		(6 "In2.Cu" signal "L3")
		(8 "In3.Cu" signal "L4GND")
		(10 "In4.Cu" signal "L5")
		(12 "In5.Cu" signal "L6GND")
		(14 "In6.Cu" signal "L7VCC")
		(16 "In7.Cu" signal "L8VCC")
		(18 "In8.Cu" signal "L9GND")
		(20 "In9.Cu" signal "L10")
		(22 "In10.Cu" signal "L11GND")
		(24 "In11.Cu" signal "L12")
		(26 "In12.Cu" signal "L13GND")
		(2 "B.Cu" signal "BOTTOM")
		(9 "F.Adhes" user "F.Adhesive")
		(11 "B.Adhes" user "B.Adhesive")
		(13 "F.Paste" user "Package Geometry/Pastemask Top")
		(15 "B.Paste" user "Package Geometry/Pastemask Bottom")
		(5 "F.SilkS" user "Ref Des/Silkscreen Top")
		(7 "B.SilkS" user "Ref Des/Silkscreen Bottom")
		(1 "F.Mask" user "Board Geometry/Soldermask Top")
		(3 "B.Mask" user "Board Geometry/Soldermask Bottom")
		(17 "Dwgs.User" user "User.Drawings")
		(19 "Cmts.User" user "User.Comments")
		(21 "Eco1.User" user "User.Eco1")
		(23 "Eco2.User" user "User.Eco2")
		(25 "Edge.Cuts" user "Board Geometry/Outline")
		(27 "Margin" user)
		(31 "F.CrtYd" user "Package Geometry/Place Bound Top")
		(29 "B.CrtYd" user "Package Geometry/Place Bound Bottom")
		(35 "F.Fab" user "Ref Des/Assembly Top")
		(33 "B.Fab" user "Ref Des/Assembly Bottom")
	)
	(footprint ""
		(layer "B.Cu")
		(at 117.1956 -71.882 -90)
		(property "Reference" "R7P19"
			(at 0 0 90)
			(layer "B.SilkS")
			(hide yes)
			(effects
				(font
					(size 1.27 1.27)
				)
				(justify mirror)
			)
		)
		(property "Value" ""
			(at 0 0 90)
			(layer "B.Fab")
			(effects
				(font
					(size 1.27 1.27)
				)
				(justify mirror)
			)
		)
		(duplicate_pad_numbers_are_jumpers no)
		(fp_poly
			(pts
				(xy 0.2794 -0.1016) (xy -0.2794 -0.1016) (xy -0.2794 0.9906) (xy 0.2794 0.9906)
			)
			(stroke
				(width 0)
				(type default)
			)
			(fill no)
			(layer "B.CrtYd")
		)
		(fp_line
			(start -0.2794 0.9906)
			(end -0.2794 -0.1016)
			(stroke
				(width 0.1)
				(type default)
			)
			(layer "B.Fab")
		)
		(fp_line
			(start 0.2794 0.9906)
			(end -0.2794 0.9906)
			(stroke
				(width 0.1)
				(type default)
			)
			(layer "B.Fab")
		)
		(fp_line
			(start -0.2794 -0.1016)
			(end 0.2794 -0.1016)
			(stroke
				(width 0.1)
				(type default)
			)
			(layer "B.Fab")
		)
		(fp_line
			(start 0.2794 -0.1016)
			(end 0.2794 0.9906)
			(stroke
				(width 0.1)
				(type default)
			)
			(layer "B.Fab")
		)
		(pad "1" smd rect
			(at 0 0 90)
			(size 0.508 0.508)
			(layers "B.Cu" "B.Mask" "B.Paste")
			(net "A_CPU1_GHJ_RCOMP2")
		)
		(pad "2" smd rect
			(at 0 0.889 90)
			(size 0.508 0.508)
			(layers "B.Cu" "B.Mask" "B.Paste")
			(net "GND")
		)
		(zone
			(layer "B.Cu")
			(hatch none 0.5)
			(connect_pads
				(clearance 0)
			)
			(min_thickness 0.25)
			(keepout
				(tracks not_allowed)
				(vias allowed)
				(pads allowed)
				(copperpour not_allowed)
				(footprints allowed)
			)
			(placement
				(enabled no)
				(sheetname "")
			)
			(fill
				(thermal_gap 0.5)
				(thermal_bridge_width 0.5)
				(island_removal_mode 0)
			)
			(polygon
				(pts
					(xy 116.5606 -71.628) (xy 116.5606 -72.136) (xy 116.9416 -72.136) (xy 116.9416 -71.628)
				)
			)
		)
		(zone
			(layer "B.Cu")
			(hatch none 0.5)
			(connect_pads
				(clearance 0)
			)
			(min_thickness 0.25)
			(keepout
				(tracks allowed)
				(vias not_allowed)
				(pads allowed)
				(copperpour not_allowed)
				(footprints allowed)
			)
			(placement
				(enabled no)
				(sheetname "")
			)
			(fill
				(thermal_gap 0.5)
				(thermal_bridge_width 0.5)
				(island_removal_mode 0)
			)
			(polygon
				(pts
					(xy 116.9416 -71.628) (xy 116.9416 -72.136) (xy 116.5606 -72.136) (xy 116.5606 -71.628)
				)
			)
		)
	)
	(footprint ""
		(layer "B.Cu")
		(at 482.65969 -58.069988 -90)
		(property "Reference" "R8E28"
			(at 0 0 90)
			(layer "B.SilkS")
			(hide yes)
			(effects
				(font
					(size 1.27 1.27)
				)
				(justify mirror)
			)
		)
		(property "Value" ""
			(at 0 0 90)
			(layer "B.Fab")
			(effects
				(font
					(size 1.27 1.27)
				)
				(justify mirror)
			)
		)
		(duplicate_pad_numbers_are_jumpers no)
		(fp_poly
			(pts
				(xy 0.2794 -0.1016) (xy -0.2794 -0.1016) (xy -0.2794 0.9906) (xy 0.2794 0.9906)
			)
			(stroke
				(width 0)
				(type default)
			)
			(fill no)
			(layer "B.CrtYd")
		)
		(fp_line
			(start -0.2794 0.9906)
			(end -0.2794 -0.1016)
			(stroke
				(width 0.1)
				(type default)
			)
			(layer "B.Fab")
		)
		(fp_line
			(start 0.2794 0.9906)
			(end -0.2794 0.9906)
			(stroke
				(width 0.1)
				(type default)
			)
			(layer "B.Fab")
		)
		(fp_line
			(start -0.2794 -0.1016)
			(end 0.2794 -0.1016)
			(stroke
				(width 0.1)
				(type default)
			)
			(layer "B.Fab")
		)
		(fp_line
			(start 0.2794 -0.1016)
			(end 0.2794 0.9906)
			(stroke
				(width 0.1)
				(type default)
			)
			(layer "B.Fab")
		)
		(pad "1" smd rect
			(at 0 0 90)
			(size 0.508 0.508)
			(layers "B.Cu" "B.Mask" "B.Paste")
			(net "FM_PE_SLOTX24_WAKE_N")
		)
		(pad "2" smd rect
			(at 0 0.889 90)
			(size 0.508 0.508)
			(layers "B.Cu" "B.Mask" "B.Paste")
			(net "FM_ALL_WAKE_N")
		)
		(zone
			(layer "B.Cu")
			(hatch none 0.5)
			(connect_pads
				(clearance 0)
			)
			(min_thickness 0.25)
			(keepout
				(tracks not_allowed)
				(vias allowed)
				(pads allowed)
				(copperpour not_allowed)
				(footprints allowed)
			)
			(placement
				(enabled no)
				(sheetname "")
			)
			(fill
				(thermal_gap 0.5)
				(thermal_bridge_width 0.5)
				(island_removal_mode 0)
			)
			(polygon
				(pts
					(xy 482.02469 -57.815988) (xy 482.02469 -58.323988) (xy 482.40569 -58.323988) (xy 482.40569 -57.815988)
				)
			)
		)
		(zone
			(layer "B.Cu")
			(hatch none 0.5)
			(connect_pads
				(clearance 0)
			)
			(min_thickness 0.25)
			(keepout
				(tracks allowed)
				(vias not_allowed)
				(pads allowed)
				(copperpour not_allowed)
				(footprints allowed)
			)
			(placement
				(enabled no)
				(sheetname "")
			)
			(fill
				(thermal_gap 0.5)
				(thermal_bridge_width 0.5)
				(island_removal_mode 0)
			)
			(polygon
				(pts
					(xy 482.40569 -57.815988) (xy 482.40569 -58.323988) (xy 482.02469 -58.323988) (xy 482.02469 -57.815988)
				)
			)
		)
	)
	(footprint ""
		(layer "B.Cu")
		(at 470.027 -61.722 -90)
		(property "Reference" "R1R17"
			(at 0 0 90)
			(layer "B.SilkS")
			(hide yes)
			(effects
				(font
					(size 1.27 1.27)
				)
				(justify mirror)
			)
		)
		(property "Value" ""
			(at 0 0 90)
			(layer "B.Fab")
			(effects
				(font
					(size 1.27 1.27)
				)
				(justify mirror)
			)
		)
		(duplicate_pad_numbers_are_jumpers no)
		(fp_poly
			(pts
				(xy 0.2794 -0.1016) (xy -0.2794 -0.1016) (xy -0.2794 0.9906) (xy 0.2794 0.9906)
			)
			(stroke
				(width 0)
				(type default)
			)
			(fill no)
			(layer "B.CrtYd")
		)
		(fp_line
			(start -0.2794 0.9906)
			(end -0.2794 -0.1016)
			(stroke
				(width 0.1)
				(type default)
			)
			(layer "B.Fab")
		)
		(fp_line
			(start 0.2794 0.9906)
			(end -0.2794 0.9906)
			(stroke
				(width 0.1)
				(type default)
			)
			(layer "B.Fab")
		)
		(fp_line
			(start -0.2794 -0.1016)
			(end 0.2794 -0.1016)
			(stroke
				(width 0.1)
				(type default)
			)
			(layer "B.Fab")
		)
		(fp_line
			(start 0.2794 -0.1016)
			(end 0.2794 0.9906)
			(stroke
				(width 0.1)
				(type default)
			)
			(layer "B.Fab")
		)
		(pad "1" smd rect
			(at 0 0 90)
			(size 0.508 0.508)
			(layers "B.Cu" "B.Mask" "B.Paste")
			(net "P3V3_STBY")
		)
		(pad "2" smd rect
			(at 0 0.889 90)
			(size 0.508 0.508)
			(layers "B.Cu" "B.Mask" "B.Paste")
			(net "SMB_PCH_MEZZ_LOM2_SDA")
		)
		(zone
			(layer "B.Cu")
			(hatch none 0.5)
			(connect_pads
				(clearance 0)
			)
			(min_thickness 0.25)
			(keepout
				(tracks not_allowed)
				(vias allowed)
				(pads allowed)
				(copperpour not_allowed)
				(footprints allowed)
			)
			(placement
				(enabled no)
				(sheetname "")
			)
			(fill
				(thermal_gap 0.5)
				(thermal_bridge_width 0.5)
				(island_removal_mode 0)
			)
			(polygon
				(pts
					(xy 469.392 -61.468) (xy 469.392 -61.976) (xy 469.773 -61.976) (xy 469.773 -61.468)
				)
			)
		)
		(zone
			(layer "B.Cu")
			(hatch none 0.5)
			(connect_pads
				(clearance 0)
			)
			(min_thickness 0.25)
			(keepout
				(tracks allowed)
				(vias not_allowed)
				(pads allowed)
				(copperpour not_allowed)
				(footprints allowed)
			)
			(placement
				(enabled no)
				(sheetname "")
			)
			(fill
				(thermal_gap 0.5)
				(thermal_bridge_width 0.5)
				(island_removal_mode 0)
			)
			(polygon
				(pts
					(xy 469.773 -61.468) (xy 469.773 -61.976) (xy 469.392 -61.976) (xy 469.392 -61.468)
				)
			)
		)
	)
	(footprint ""
		(layer "B.Cu")
		(at 29.690568 -135.763)
		(property "Reference" "R9L11"
			(at 0 0 0)
			(layer "B.SilkS")
			(hide yes)
			(effects
				(font
					(size 1.27 1.27)
				)
				(justify mirror)
			)
		)
		(property "Value" ""
			(at 0 0 0)
			(layer "B.Fab")
			(effects
				(font
					(size 1.27 1.27)
				)
				(justify mirror)
			)
		)
		(duplicate_pad_numbers_are_jumpers no)
		(fp_poly
			(pts
				(xy 0.2794 -0.1016) (xy -0.2794 -0.1016) (xy -0.2794 0.9906) (xy 0.2794 0.9906)
			)
			(stroke
				(width 0)
				(type default)
			)
			(fill no)
			(layer "B.CrtYd")
		)
		(fp_line
			(start -0.2794 -0.1016)
			(end 0.2794 -0.1016)
			(stroke
				(width 0.1)
				(type default)
			)
			(layer "B.Fab")
		)
		(fp_line
			(start -0.2794 0.9906)
			(end -0.2794 -0.1016)
			(stroke
				(width 0.1)
				(type default)
			)
			(layer "B.Fab")
		)
		(fp_line
			(start 0.2794 -0.1016)
			(end 0.2794 0.9906)
			(stroke
				(width 0.1)
				(type default)
			)
			(layer "B.Fab")
		)
		(fp_line
			(start 0.2794 0.9906)
			(end -0.2794 0.9906)
			(stroke
				(width 0.1)
				(type default)
			)
			(layer "B.Fab")
		)
		(pad "1" smd rect
			(at 0 0 180)
			(size 0.508 0.508)
			(layers "B.Cu" "B.Mask" "B.Paste")
			(net "M_K_VREF")
		)
		(pad "2" smd rect
			(at 0 0.889 180)
			(size 0.508 0.508)
			(layers "B.Cu" "B.Mask" "B.Paste")
			(net "GND")
		)
		(zone
			(layer "B.Cu")
			(hatch none 0.5)
			(connect_pads
				(clearance 0)
			)
			(min_thickness 0.25)
			(keepout
				(tracks allowed)
				(vias not_allowed)
				(pads allowed)
				(copperpour not_allowed)
				(footprints allowed)
			)
			(placement
				(enabled no)
				(sheetname "")
			)
			(fill
				(thermal_gap 0.5)
				(thermal_bridge_width 0.5)
				(island_removal_mode 0)
			)
			(polygon
				(pts
					(xy 29.944568 -135.509) (xy 29.436568 -135.509) (xy 29.436568 -135.128) (xy 29.944568 -135.128)
				)
			)
		)
		(zone
			(layer "B.Cu")
			(hatch none 0.5)
			(connect_pads
				(clearance 0)
			)
			(min_thickness 0.25)
			(keepout
				(tracks not_allowed)
				(vias allowed)
				(pads allowed)
				(copperpour not_allowed)
				(footprints allowed)
			)
			(placement
				(enabled no)
				(sheetname "")
			)
			(fill
				(thermal_gap 0.5)
				(thermal_bridge_width 0.5)
				(island_removal_mode 0)
			)
			(polygon
				(pts
					(xy 29.944568 -135.128) (xy 29.436568 -135.128) (xy 29.436568 -135.509) (xy 29.944568 -135.509)
				)
			)
		)
	)
	(footprint ""
		(layer "B.Cu")
		(at 351.421192 -77.834236 180)
		(property "Reference" "C3P28"
			(at 0 0 0)
			(layer "B.SilkS")
			(hide yes)
			(effects
				(font
					(size 1.27 1.27)
				)
				(justify mirror)
			)
		)
		(property "Value" ""
			(at 0 0 0)
			(layer "B.Fab")
			(effects
				(font
					(size 1.27 1.27)
				)
				(justify mirror)
			)
		)
		(duplicate_pad_numbers_are_jumpers no)
		(fp_poly
			(pts
				(xy -0.3048 -0.1016) (xy -0.3048 0.9906) (xy 0.3048 0.9906) (xy 0.3048 -0.1016)
			)
			(stroke
				(width 0)
				(type default)
			)
			(fill no)
			(layer "B.CrtYd")
		)
		(fp_line
			(start 0.3048 0.9906)
			(end -0.3048 0.9906)
			(stroke
				(width 0.1)
				(type default)
			)
			(layer "B.Fab")
		)
		(fp_line
			(start 0.3048 -0.1016)
			(end 0.3048 0.9906)
			(stroke
				(width 0.1)
				(type default)
			)
			(layer "B.Fab")
		)
		(fp_line
			(start -0.3048 0.9906)
			(end -0.3048 -0.1016)
			(stroke
				(width 0.1)
				(type default)
			)
			(layer "B.Fab")
		)
		(fp_line
			(start -0.3048 -0.1016)
			(end 0.3048 -0.1016)
			(stroke
				(width 0.1)
				(type default)
			)
			(layer "B.Fab")
		)
		(pad "1" smd rect
			(at 0 0)
			(size 0.508 0.508)
			(layers "B.Cu" "B.Mask" "B.Paste")
			(net "P3E_CPU0_PE1_SS_TXN<4>")
		)
		(pad "2" smd rect
			(at 0 0.889)
			(size 0.508 0.508)
			(layers "B.Cu" "B.Mask" "B.Paste")
			(net "P3E_CPU0_PE1_PCH_TXN<4>")
		)
		(zone
			(layer "B.Cu")
			(hatch none 0.5)
			(connect_pads
				(clearance 0)
			)
			(min_thickness 0.25)
			(keepout
				(tracks not_allowed)
				(vias allowed)
				(pads allowed)
				(copperpour not_allowed)
				(footprints allowed)
			)
			(placement
				(enabled no)
				(sheetname "")
			)
			(fill
				(thermal_gap 0.5)
				(thermal_bridge_width 0.5)
				(island_removal_mode 0)
			)
			(polygon
				(pts
					(xy 351.167192 -78.469236) (xy 351.675192 -78.469236) (xy 351.675192 -78.088236) (xy 351.167192 -78.088236)
				)
			)
		)
		(zone
			(layer "B.Cu")
			(hatch none 0.5)
			(connect_pads
				(clearance 0)
			)
			(min_thickness 0.25)
			(keepout
				(tracks allowed)
				(vias not_allowed)
				(pads allowed)
				(copperpour not_allowed)
				(footprints allowed)
			)
			(placement
				(enabled no)
				(sheetname "")
			)
			(fill
				(thermal_gap 0.5)
				(thermal_bridge_width 0.5)
				(island_removal_mode 0)
			)
			(polygon
				(pts
					(xy 351.167192 -78.088236) (xy 351.675192 -78.088236) (xy 351.675192 -78.469236) (xy 351.167192 -78.469236)
				)
			)
		)
	)
	(footprint ""
		(layer "B.Cu")
		(at 440.458606 -16.164306 90)
		(property "Reference" "R1U30"
			(at 0 0 90)
			(layer "B.SilkS")
			(hide yes)
			(effects
				(font
					(size 1.27 1.27)
				)
				(justify mirror)
			)
		)
		(property "Value" ""
			(at 0 0 90)
			(layer "B.Fab")
			(effects
				(font
					(size 1.27 1.27)
				)
				(justify mirror)
			)
		)
		(duplicate_pad_numbers_are_jumpers no)
		(fp_poly
			(pts
				(xy 0.2794 -0.1016) (xy -0.2794 -0.1016) (xy -0.2794 0.9906) (xy 0.2794 0.9906)
			)
			(stroke
				(width 0)
				(type default)
			)
			(fill no)
			(layer "B.CrtYd")
		)
		(fp_line
			(start 0.2794 -0.1016)
			(end 0.2794 0.9906)
			(stroke
				(width 0.1)
				(type default)
			)
			(layer "B.Fab")
		)
		(fp_line
			(start -0.2794 -0.1016)
			(end 0.2794 -0.1016)
			(stroke
				(width 0.1)
				(type default)
			)
			(layer "B.Fab")
		)
		(fp_line
			(start 0.2794 0.9906)
			(end -0.2794 0.9906)
			(stroke
				(width 0.1)
				(type default)
			)
			(layer "B.Fab")
		)
		(fp_line
			(start -0.2794 0.9906)
			(end -0.2794 -0.1016)
			(stroke
				(width 0.1)
				(type default)
			)
			(layer "B.Fab")
		)
		(pad "1" smd rect
			(at 0 0 270)
			(size 0.508 0.508)
			(layers "B.Cu" "B.Mask" "B.Paste")
			(net "PD_DIR_2")
		)
		(pad "2" smd rect
			(at 0 0.889 270)
			(size 0.508 0.508)
			(layers "B.Cu" "B.Mask" "B.Paste")
			(net "GND")
		)
		(zone
			(layer "B.Cu")
			(hatch none 0.5)
			(connect_pads
				(clearance 0)
			)
			(min_thickness 0.25)
			(keepout
				(tracks allowed)
				(vias not_allowed)
				(pads allowed)
				(copperpour not_allowed)
				(footprints allowed)
			)
			(placement
				(enabled no)
				(sheetname "")
			)
			(fill
				(thermal_gap 0.5)
				(thermal_bridge_width 0.5)
				(island_removal_mode 0)
			)
			(polygon
				(pts
					(xy 440.712606 -16.418306) (xy 440.712606 -15.910306) (xy 441.093606 -15.910306) (xy 441.093606 -16.418306)
				)
			)
		)
		(zone
			(layer "B.Cu")
			(hatch none 0.5)
			(connect_pads
				(clearance 0)
			)
			(min_thickness 0.25)
			(keepout
				(tracks not_allowed)
				(vias allowed)
				(pads allowed)
				(copperpour not_allowed)
				(footprints allowed)
			)
			(placement
				(enabled no)
				(sheetname "")
			)
			(fill
				(thermal_gap 0.5)
				(thermal_bridge_width 0.5)
				(island_removal_mode 0)
			)
			(polygon
				(pts
					(xy 441.093606 -16.418306) (xy 441.093606 -15.910306) (xy 440.712606 -15.910306) (xy 440.712606 -16.418306)
				)
			)
		)
	)
	(footprint ""
		(layer "B.Cu")
		(at 394.95984 -37.9984 180)
		(property "Reference" "U8G1"
			(at 0 0 0)
			(layer "B.SilkS")
			(hide yes)
			(effects
				(font
					(size 1.27 1.27)
				)
				(justify mirror)
			)
		)
		(property "Value" "*"
			(at 2.3622 -8.3185 180)
			(unlocked yes)
			(layer "B.Fab")
			(hide yes)
			(effects
				(font
					(size 1.27 1.016)
					(thickness 0.1524)
				)
				(justify mirror)
			)
		)
		(property "Device Type" "SN74LVC2G07DCKR-GP_DISCRET-G4-A"
			(at 2.3622 -10.2235 180)
			(unlocked yes)
			(layer "B.Fab")
			(hide yes)
			(effects
				(font
					(size 1.27 1.016)
					(thickness 0.1524)
				)
				(justify mirror)
			)
		)
		(duplicate_pad_numbers_are_jumpers no)
		(fp_line
			(start 1.5494 1.7907)
			(end 1.5494 0.8255)
			(stroke
				(width 0.3302)
				(type default)
			)
			(layer "B.SilkS")
		)
		(fp_line
			(start 1.4478 1.7018)
			(end -1.4478 1.7018)
			(stroke
				(width 0.1524)
				(type default)
			)
			(layer "B.SilkS")
		)
		(fp_line
			(start 1.4478 -1.7018)
			(end 1.4478 1.7018)
			(stroke
				(width 0.1524)
				(type default)
			)
			(layer "B.SilkS")
		)
		(fp_line
			(start 0.5715 1.7907)
			(end 1.5494 1.7907)
			(stroke
				(width 0.3302)
				(type default)
			)
			(layer "B.SilkS")
		)
		(fp_line
			(start -1.4478 1.7018)
			(end -1.4478 -1.7018)
			(stroke
				(width 0.1524)
				(type default)
			)
			(layer "B.SilkS")
		)
		(fp_line
			(start -1.4478 -1.7018)
			(end 1.4478 -1.7018)
			(stroke
				(width 0.1524)
				(type default)
			)
			(layer "B.SilkS")
		)
		(fp_poly
			(pts
				(xy 0.6604 1.7272) (xy 1.016 2.0828) (xy 0.3048 2.0828)
			)
			(stroke
				(width 0)
				(type default)
			)
			(fill yes)
			(layer "B.SilkS")
		)
		(fp_poly
			(pts
				(xy 1.524 -1.778) (xy -1.524 -1.778) (xy -1.524 1.778) (xy 1.524 1.778)
			)
			(stroke
				(width 0)
				(type default)
			)
			(fill no)
			(layer "B.CrtYd")
		)
		(fp_poly
			(pts
				(xy 1.524 -1.778) (xy -1.524 -1.778) (xy -1.524 1.778) (xy 1.524 1.778)
			)
			(stroke
				(width 0)
				(type default)
			)
			(fill no)
			(layer "B.Fab")
		)
		(pad "1" smd rect
			(at 0.65024 0.9398)
			(size 0.4064 1.016)
			(layers "B.Cu" "B.Mask" "B.Paste")
			(net "RST_PCH_SYSRST_BTN_OUT_N")
		)
		(pad "2" smd rect
			(at 0 0.9398)
			(size 0.4064 1.016)
			(layers "B.Cu" "B.Mask" "B.Paste")
			(net "GND")
		)
		(pad "3" smd rect
			(at -0.65024 0.9398)
			(size 0.4064 1.016)
			(layers "B.Cu" "B.Mask" "B.Paste")
			(net "FM_PCH_PWRBTN_OUT_N")
		)
		(pad "4" smd rect
			(at -0.65024 -0.9398)
			(size 0.4064 1.016)
			(layers "B.Cu" "B.Mask" "B.Paste")
			(net "FM_PCH_PWRBTN_R_N")
		)
		(pad "5" smd rect
			(at 0 -0.9398)
			(size 0.4064 1.016)
			(layers "B.Cu" "B.Mask" "B.Paste")
			(net "P3V3_STBY")
		)
		(pad "6" smd rect
			(at 0.65024 -0.9398)
			(size 0.4064 1.016)
			(layers "B.Cu" "B.Mask" "B.Paste")
			(net "RST_BMC_SYSRST_BTN_OUT_B_R_N")
		)
	)
)
